# T6G (Grand Teton) — schematic netlist excerpt (pin names and nets, part order shuffled) for the footprints in the layout excerpt that follows; sources: Cadence DE-HDL packaged netlist, KiCad conversion of 04192023_DAF0TMB3IC0_F0TG_MB_C_brd_V02_OCP.brd

R727  Q_RES  4.7K 5% CHIP  pkg 0201LF  page 320 : A = P1V8_CPU1_RT_1D ; B = MODE_RT_CPU1_P0
PC217  Q_CAP  0.22UF 16V 10% X7R  pkg 0402  page 208 : A = SW_PVDD11_S3_P0_BOOT1_RC ; B = SW_PVDD11_S3_P0_PH1
PR3851  Q_RES  10K 1% CHIP  pkg 0402LF  page 141 : A = P12V_OCP_FLTB_2 ; B = P3V3_AUX

(kicad_pcb
	(version 20260206)
	(generator "pcbnew")
	(generator_version "10.0")
	(general
		(thickness 1.6)
		(legacy_teardrops no)
	)
	(paper "A4")
	(title_block
		(title "04192023_DAF0TMB3IC0_F0TG_MB_C_brd_V02_OCP.brd")
		(comment 1 "Grand Teton / footprints 1321-1323 of 8354")
	)
	(layers
		(0 "F.Cu" signal "TOP")
		(4 "In1.Cu" signal "GND")
		(6 "In2.Cu" signal "IN1")
		(8 "In3.Cu" signal "GND1")
		(10 "In4.Cu" signal "IN2")
		(12 "In5.Cu" signal "GND2")
		(14 "In6.Cu" signal "IN3")
		(16 "In7.Cu" signal "GND3")
		(18 "In8.Cu" signal "VCC")
		(20 "In9.Cu" signal "VCC1")
		(22 "In10.Cu" signal "GND4")
		(24 "In11.Cu" signal "IN4")
		(26 "In12.Cu" signal "GND5")
		(28 "In13.Cu" signal "IN5")
		(30 "In14.Cu" signal "GND6")
		(32 "In15.Cu" signal "IN6")
		(34 "In16.Cu" signal "GND7")
		(2 "B.Cu" signal "BOTTOM")
		(9 "F.Adhes" user "F.Adhesive")
		(11 "B.Adhes" user "B.Adhesive")
		(13 "F.Paste" user "Package Geometry/Pastemask Top")
		(15 "B.Paste" user "Package Geometry/Pastemask Bottom")
		(5 "F.SilkS" user "Ref Des/Silkscreen Top")
		(7 "B.SilkS" user "Ref Des/Silkscreen Bottom")
		(1 "F.Mask" user "Board Geometry/Soldermask Top")
		(3 "B.Mask" user "Board Geometry/Soldermask Bottom")
		(17 "Dwgs.User" user "User.Drawings")
		(19 "Cmts.User" user "User.Comments")
		(21 "Eco1.User" user "User.Eco1")
		(23 "Eco2.User" user "User.Eco2")
		(25 "Edge.Cuts" user "Board Geometry/Outline")
		(27 "Margin" user)
		(31 "F.CrtYd" user "Package Geometry/Place Bound Top")
		(29 "B.CrtYd" user "Package Geometry/Place Bound Bottom")
		(35 "F.Fab" user "Ref Des/Assembly Top")
		(33 "B.Fab" user "Ref Des/Assembly Bottom")
	)
	(footprint ""
		(layer "F.Cu")
		(at 425.429934 -355.718364 -90)
		(property "Reference" "PC217"
			(at 0 0 270)
			(layer "F.SilkS")
			(hide yes)
			(effects
				(font
					(size 1.27 1.27)
				)
			)
		)
		(property "Value" ""
			(at 0 0 270)
			(layer "F.Fab")
			(effects
				(font
					(size 1.27 1.27)
				)
			)
		)
		(duplicate_pad_numbers_are_jumpers no)
		(fp_line
			(start -0.7874 0.4064)
			(end -0.7874 -0.4064)
			(stroke
				(width 0.1524)
				(type default)
			)
			(layer "F.SilkS")
		)
		(fp_line
			(start 0.7874 0.4064)
			(end -0.7874 0.4064)
			(stroke
				(width 0.1524)
				(type default)
			)
			(layer "F.SilkS")
		)
		(fp_line
			(start -0.7874 -0.4064)
			(end 0.7874 -0.4064)
			(stroke
				(width 0.1524)
				(type default)
			)
			(layer "F.SilkS")
		)
		(fp_line
			(start 0.7874 -0.4064)
			(end 0.7874 0.4064)
			(stroke
				(width 0.1524)
				(type default)
			)
			(layer "F.SilkS")
		)
		(fp_line
			(start -0.67945 0.3048)
			(end -0.67945 -0.305054)
			(stroke
				(width 0.1)
				(type default)
			)
			(layer "F.Fab")
		)
		(fp_line
			(start -0.12065 0.3048)
			(end -0.67945 0.3048)
			(stroke
				(width 0.1)
				(type default)
			)
			(layer "F.Fab")
		)
		(fp_line
			(start 0.120396 0.3048)
			(end 0.120396 0.2794)
			(stroke
				(width 0.1)
				(type default)
			)
			(layer "F.Fab")
		)
		(fp_line
			(start 0.67945 0.3048)
			(end 0.120396 0.3048)
			(stroke
				(width 0.1)
				(type default)
			)
			(layer "F.Fab")
		)
		(fp_line
			(start -0.12065 0.2794)
			(end -0.12065 0.3048)
			(stroke
				(width 0.1)
				(type default)
			)
			(layer "F.Fab")
		)
		(fp_line
			(start 0.120396 0.2794)
			(end -0.12065 0.2794)
			(stroke
				(width 0.1)
				(type default)
			)
			(layer "F.Fab")
		)
		(fp_line
			(start -0.12065 -0.2794)
			(end 0.12065 -0.2794)
			(stroke
				(width 0.1)
				(type default)
			)
			(layer "F.Fab")
		)
		(fp_line
			(start 0.12065 -0.2794)
			(end 0.12065 -0.3048)
			(stroke
				(width 0.1)
				(type default)
			)
			(layer "F.Fab")
		)
		(fp_line
			(start 0.12065 -0.3048)
			(end 0.67945 -0.3048)
			(stroke
				(width 0.1)
				(type default)
			)
			(layer "F.Fab")
		)
		(fp_line
			(start 0.67945 -0.3048)
			(end 0.67945 0.3048)
			(stroke
				(width 0.1)
				(type default)
			)
			(layer "F.Fab")
		)
		(fp_line
			(start -0.67945 -0.305054)
			(end -0.12065 -0.305054)
			(stroke
				(width 0.1)
				(type default)
			)
			(layer "F.Fab")
		)
		(fp_line
			(start -0.12065 -0.305054)
			(end -0.12065 -0.2794)
			(stroke
				(width 0.1)
				(type default)
			)
			(layer "F.Fab")
		)
		(pad "1" smd circle
			(at -0.40005 0 270)
			(size 0 0)
			(layers "F.Cu" "F.Mask" "F.Paste")
			(net "SW_PVDD11_S3_P0_BOOT1_RC")
		)
		(pad "2" smd circle
			(at 0.40005 0 270)
			(size 0 0)
			(layers "F.Cu" "F.Mask" "F.Paste")
			(net "SW_PVDD11_S3_P0_PH1")
		)
	)
	(footprint ""
		(layer "F.Cu")
		(at 40.386 -390.398 90)
		(property "Reference" "R727"
			(at 0 0 90)
			(layer "F.SilkS")
			(hide yes)
			(effects
				(font
					(size 1.27 1.27)
				)
			)
		)
		(property "Value" ""
			(at 0 0 90)
			(layer "F.Fab")
			(effects
				(font
					(size 1.27 1.27)
				)
			)
		)
		(duplicate_pad_numbers_are_jumpers no)
		(fp_line
			(start 0.32512 -0.175006)
			(end 0.32512 0.175006)
			(stroke
				(width 0.1)
				(type default)
			)
			(layer "F.Fab")
		)
		(fp_line
			(start -0.32512 -0.175006)
			(end 0.32512 -0.175006)
			(stroke
				(width 0.1)
				(type default)
			)
			(layer "F.Fab")
		)
		(fp_line
			(start 0.32512 0.175006)
			(end -0.32512 0.175006)
			(stroke
				(width 0.1)
				(type default)
			)
			(layer "F.Fab")
		)
		(fp_line
			(start -0.32512 0.175006)
			(end -0.32512 -0.175006)
			(stroke
				(width 0.1)
				(type default)
			)
			(layer "F.Fab")
		)
		(pad "1" smd rect
			(at -0.2667 0 90)
			(size 0.3048 0.381)
			(layers "F.Cu" "F.Mask" "F.Paste")
			(net "P1V8_CPU1_RT_1D")
		)
		(pad "2" smd rect
			(at 0.2667 0 270)
			(size 0.3048 0.381)
			(layers "F.Cu" "F.Mask" "F.Paste")
			(net "MODE_RT_CPU1_P0")
		)
	)
	(footprint ""
		(layer "F.Cu")
		(at 63.194438 -29.398722 180)
		(property "Reference" "PR3851"
			(at 0 0 180)
			(layer "F.SilkS")
			(hide yes)
			(effects
				(font
					(size 1.27 1.27)
				)
			)
		)
		(property "Value" ""
			(at 0 0 180)
			(layer "F.Fab")
			(effects
				(font
					(size 1.27 1.27)
				)
			)
		)
		(duplicate_pad_numbers_are_jumpers no)
		(fp_line
			(start 0.7874 0.4064)
			(end -0.7874 0.4064)
			(stroke
				(width 0.1524)
				(type default)
			)
			(layer "F.SilkS")
		)
		(fp_line
			(start 0.7874 -0.4064)
			(end 0.7874 0.4064)
			(stroke
				(width 0.1524)
				(type default)
			)
			(layer "F.SilkS")
		)
		(fp_line
			(start -0.7874 0.4064)
			(end -0.7874 -0.4064)
			(stroke
				(width 0.1524)
				(type default)
			)
			(layer "F.SilkS")
		)
		(fp_line
			(start -0.7874 -0.4064)
			(end 0.7874 -0.4064)
			(stroke
				(width 0.1524)
				(type default)
			)
			(layer "F.SilkS")
		)
		(fp_line
			(start 0.67945 0.3048)
			(end 0.120396 0.3048)
			(stroke
				(width 0.1)
				(type default)
			)
			(layer "F.Fab")
		)
		(fp_line
			(start 0.67945 -0.3048)
			(end 0.67945 0.3048)
			(stroke
				(width 0.1)
				(type default)
			)
			(layer "F.Fab")
		)
		(fp_line
			(start 0.12065 -0.2794)
			(end 0.12065 -0.3048)
			(stroke
				(width 0.1)
				(type default)
			)
			(layer "F.Fab")
		)
		(fp_line
			(start 0.12065 -0.3048)
			(end 0.67945 -0.3048)
			(stroke
				(width 0.1)
				(type default)
			)
			(layer "F.Fab")
		)
		(fp_line
			(start 0.120396 0.3048)
			(end 0.120396 0.2794)
			(stroke
				(width 0.1)
				(type default)
			)
			(layer "F.Fab")
		)
		(fp_line
			(start 0.120396 0.2794)
			(end -0.12065 0.2794)
			(stroke
				(width 0.1)
				(type default)
			)
			(layer "F.Fab")
		)
		(fp_line
			(start -0.12065 0.3048)
			(end -0.67945 0.3048)
			(stroke
				(width 0.1)
				(type default)
			)
			(layer "F.Fab")
		)
		(fp_line
			(start -0.12065 0.2794)
			(end -0.12065 0.3048)
			(stroke
				(width 0.1)
				(type default)
			)
			(layer "F.Fab")
		)
		(fp_line
			(start -0.12065 -0.2794)
			(end 0.12065 -0.2794)
			(stroke
				(width 0.1)
				(type default)
			)
			(layer "F.Fab")
		)
		(fp_line
			(start -0.12065 -0.305054)
			(end -0.12065 -0.2794)
			(stroke
				(width 0.1)
				(type default)
			)
			(layer "F.Fab")
		)
		(fp_line
			(start -0.67945 0.3048)
			(end -0.67945 -0.305054)
			(stroke
				(width 0.1)
				(type default)
			)
			(layer "F.Fab")
		)
		(fp_line
			(start -0.67945 -0.305054)
			(end -0.12065 -0.305054)
			(stroke
				(width 0.1)
				(type default)
			)
			(layer "F.Fab")
		)
		(pad "1" smd circle
			(at -0.40005 0 180)
			(size 0 0)
			(layers "F.Cu" "F.Mask" "F.Paste")
			(net "P12V_OCP_FLTB_2")
		)
		(pad "2" smd circle
			(at 0.40005 0 180)
			(size 0 0)
			(layers "F.Cu" "F.Mask" "F.Paste")
			(net "P3V3_AUX")
		)
	)
)
